# Stackup_F0T_PDB_Converter_10L_2p36mm_IT-170GT_RTF_Rev0p2_20211201.xls — Manufacuring violation (pcb-stackup)
| Description | Quanta layout design rule | The stackup design rule |  |
| Min. Innerlayer Line Width, 0.5 oz copper (mil) | 3 | NA | Normal |
| Min. Innerlayer Space, 0.5 oz copper (mil) | 3.5 | NA | Medium |
| Min. Innerlayer Line Width,   1 oz copper (mil) | 4 | 4 | High |
| Min. Innerlayer Space, 1 oz copper (mil) | 4 | NA |  |
| Min. Innerlayer Line Width,   2oz copper (mil) | 6 | NA |  |
| Min. Innerlayer Space,  2oz copper (mil) | 6 | NA |  |
| Min. Outerlayer line width, 0.5oz copper foil (mil) | 3.5 | 4 |  |
| Min. Outerlayer Space, 0.5oz copper foil (mil) | 3.5 | NA |  |
| Min. Inner Core/PP thickness (mil) | 3 | 6 |  |
| Max. Aspect Ratio for min. DHS | 12.24 | 9.48 |  |
